(kicad_pcb
	(version 20241229)
	(generator "pcbnew")
	(generator_version "9.0")
	(general
		(thickness 1.62)
		(legacy_teardrops no)
	)
	(paper "A3")
	(title_block
		(title "COM Express 7 Baseboard")
		(date "2025-02-04")
		(rev "1.1.2")
		(company "Antmicro Ltd")
		(comment 1 "www.antmicro.com")
		(comment 9 "footprint 253 of 802 (J2), pads 1-40 of 55")
	)
	(layers
		(0 "F.Cu" signal)
		(4 "In1.Cu" signal)
		(6 "In2.Cu" signal)
		(8 "In3.Cu" signal)
		(10 "In4.Cu" signal)
		(12 "In5.Cu" signal)
		(14 "In6.Cu" signal)
		(2 "B.Cu" signal)
		(9 "F.Adhes" user "F.Adhesive")
		(11 "B.Adhes" user "B.Adhesive")
		(13 "F.Paste" user)
		(15 "B.Paste" user)
		(5 "F.SilkS" user "F.Silkscreen")
		(7 "B.SilkS" user "B.Silkscreen")
		(1 "F.Mask" user)
		(3 "B.Mask" user)
		(17 "Dwgs.User" user "User.Drawings")
		(19 "Cmts.User" user "User.Comments")
		(21 "Eco1.User" user "User.Eco1")
		(23 "Eco2.User" user "User.Eco2")
		(25 "Edge.Cuts" user)
		(27 "Margin" user)
		(31 "F.CrtYd" user "F.Courtyard")
		(29 "B.CrtYd" user "B.Courtyard")
		(35 "F.Fab" user)
		(33 "B.Fab" user)
	)
	(footprint "antmicro-footprints:Conn_Bel-Fuse_SFP+_2x20_SS-79100-010"
		(locked yes)
		(layer "F.Cu")
		(at 142.55 162.31 -90)
		(property "Reference" "J2"
			(at 8.75 46.6 0)
			(unlocked yes)
			(layer "F.SilkS")
			(effects
				(font
					(size 0.7 0.7)
					(thickness 0.15)
				)
				(justify left bottom)
			)
		)
		(property "Value" "Bel-Fuse_SFP+_2x20_SS-79100-010"
			(at 9.45 1.2 270)
			(unlocked yes)
			(layer "F.Fab")
			(effects
				(font
					(size 0.7 0.7)
					(thickness 0.15)
				)
				(justify left bottom)
			)
		)
		(property "Datasheet" "https://www.belfuse.com/resources/datasheets/stewartconnector/ds-STW-SFP-cages.pdf"
			(at 0 0 270)
			(layer "F.Fab")
			(hide yes)
			(effects
				(font
					(size 1.27 1.27)
					(thickness 0.15)
				)
			)
		)
		(property "Author" "Antmicro"
			(at -19.76 304.86 0)
			(layer "F.Fab")
			(hide yes)
			(effects
				(font
					(size 1 1)
					(thickness 0.15)
				)
			)
		)
		(property "License" "Apache-2.0"
			(at -19.76 304.86 0)
			(layer "F.Fab")
			(hide yes)
			(effects
				(font
					(size 1 1)
					(thickness 0.15)
				)
			)
		)
		(property "MPN" "SS-79100-010"
			(at -19.76 304.86 0)
			(layer "F.Fab")
			(hide yes)
			(effects
				(font
					(size 1 1)
					(thickness 0.15)
				)
			)
		)
		(property "Manufacturer" "Bel Fuse"
			(at -19.76 304.86 0)
			(layer "F.Fab")
			(hide yes)
			(effects
				(font
					(size 1 1)
					(thickness 0.15)
				)
			)
		)
		(sheetname "2xSFP+")
		(sheetfile "2xSFP+.kicad_sch")
		(attr through_hole)
		(pad "" np_thru_hole circle
			(at -5.5 0 270)
			(size 1.85 1.85)
			(drill 1.85)
			(layers "F&B.Cu" "*.Mask")
		)
		(pad "" np_thru_hole circle
			(at 5.5 -7.5 270)
			(size 1.85 1.85)
			(drill 1.85)
			(layers "F&B.Cu" "*.Mask")
		)
		(pad "L1" thru_hole circle
			(at 3.4 0.74 270)
			(size 0.86 0.86)
			(drill 0.46)
			(layers "*.Cu" "*.Mask")
			(remove_unused_layers no)
			(net 1 "GND")
			(pinfunction "V_{EE}(T)")
			(pintype "passive")
			(teardrops
				(best_length_ratio 0.4)
				(max_length 1)
				(best_width_ratio 0.9)
				(max_width 2)
				(curved_edges yes)
				(filter_ratio 0.9)
				(enabled yes)
				(allow_two_segments yes)
				(prefer_zone_connections yes)
			)
		)
		(pad "L2" thru_hole circle
			(at 2.6 -0.65 270)
			(size 0.86 0.86)
			(drill 0.46)
			(layers "*.Cu" "*.Mask")
			(remove_unused_layers no)
			(net 876 "Net-(J2B-TX_{FAULT})")
			(pinfunction "TX_{FAULT}")
			(pintype "open_collector")
			(teardrops
				(best_length_ratio 0.4)
				(max_length 1)
				(best_width_ratio 0.9)
				(max_width 2)
				(curved_edges yes)
				(filter_ratio 0.9)
				(enabled yes)
				(allow_two_segments yes)
				(prefer_zone_connections yes)
			)
		)
		(pad "L3" thru_hole circle
			(at 1.8 0.74 270)
			(size 0.86 0.86)
			(drill 0.46)
			(layers "*.Cu" "*.Mask")
			(remove_unused_layers no)
			(net 893 "Net-(J2B-TX_{DISABLE})")
			(pinfunction "TX_{DISABLE}")
			(pintype "input")
			(teardrops
				(best_length_ratio 0.4)
				(max_length 1)
				(best_width_ratio 0.9)
				(max_width 2)
				(curved_edges yes)
				(filter_ratio 0.9)
				(enabled yes)
				(allow_two_segments yes)
				(prefer_zone_connections yes)
			)
		)
		(pad "L4" thru_hole circle
			(at 1 -0.65 270)
			(size 0.86 0.86)
			(drill 0.46)
			(layers "*.Cu" "*.Mask")
			(remove_unused_layers no)
			(net 874 "/2xSFP+/SDA1")
			(pinfunction "SDA")
			(pintype "bidirectional")
			(teardrops
				(best_length_ratio 0.4)
				(max_length 1)
				(best_width_ratio 0.9)
				(max_width 2)
				(curved_edges yes)
				(filter_ratio 0.9)
				(enabled yes)
				(allow_two_segments yes)
				(prefer_zone_connections yes)
			)
		)
		(pad "L5" thru_hole circle
			(at 0.2 0.74 270)
			(size 0.86 0.86)
			(drill 0.46)
			(layers "*.Cu" "*.Mask")
			(remove_unused_layers no)
			(net 875 "/2xSFP+/SCL1")
			(pinfunction "SCL")
			(pintype "bidirectional")
			(teardrops
				(best_length_ratio 0.4)
				(max_length 1)
				(best_width_ratio 0.9)
				(max_width 2)
				(curved_edges yes)
				(filter_ratio 0.9)
				(enabled yes)
				(allow_two_segments yes)
				(prefer_zone_connections yes)
			)
		)
		(pad "L6" thru_hole circle
			(at -0.6 -0.65 270)
			(size 0.86 0.86)
			(drill 0.46)
			(layers "*.Cu" "*.Mask")
			(remove_unused_layers no)
			(net 894 "Net-(J2B-MOD_{ABS})")
			(pinfunction "MOD_{ABS}")
			(pintype "passive")
			(teardrops
				(best_length_ratio 0.4)
				(max_length 1)
				(best_width_ratio 0.9)
				(max_width 2)
				(curved_edges yes)
				(filter_ratio 0.9)
				(enabled yes)
				(allow_two_segments yes)
				(prefer_zone_connections yes)
			)
		)
		(pad "L7" thru_hole circle
			(at -1.4 0.74 270)
			(size 0.86 0.86)
			(drill 0.46)
			(layers "*.Cu" "*.Mask")
			(remove_unused_layers no)
			(net 895 "Net-(J2B-RS0)")
			(pinfunction "RS0")
			(pintype "input")
			(teardrops
				(best_length_ratio 0.4)
				(max_length 1)
				(best_width_ratio 0.9)
				(max_width 2)
				(curved_edges yes)
				(filter_ratio 0.9)
				(enabled yes)
				(allow_two_segments yes)
				(prefer_zone_connections yes)
			)
		)
		(pad "L8" thru_hole circle
			(at -2.2 -0.65 270)
			(size 0.86 0.86)
			(drill 0.46)
			(layers "*.Cu" "*.Mask")
			(remove_unused_layers no)
			(net 896 "Net-(J2B-RX_{LOS})")
			(pinfunction "RX_{LOS}")
			(pintype "open_collector")
			(teardrops
				(best_length_ratio 0.4)
				(max_length 1)
				(best_width_ratio 0.9)
				(max_width 2)
				(curved_edges yes)
				(filter_ratio 0.9)
				(enabled yes)
				(allow_two_segments yes)
				(prefer_zone_connections yes)
			)
		)
		(pad "L9" thru_hole circle
			(at -3 0.74 270)
			(size 0.86 0.86)
			(drill 0.46)
			(layers "*.Cu" "*.Mask")
			(remove_unused_layers no)
			(net 897 "Net-(J2B-RS1)")
			(pinfunction "RS1")
			(pintype "input")
			(teardrops
				(best_length_ratio 0.4)
				(max_length 1)
				(best_width_ratio 0.9)
				(max_width 2)
				(curved_edges yes)
				(filter_ratio 0.9)
				(enabled yes)
				(allow_two_segments yes)
				(prefer_zone_connections yes)
			)
		)
		(pad "L10" thru_hole circle
			(at -3.8 -0.65 270)
			(size 0.86 0.86)
			(drill 0.46)
			(layers "*.Cu" "*.Mask")
			(remove_unused_layers no)
			(net 1 "GND")
			(pinfunction "V_{EE}(R)")
			(pintype "passive")
			(teardrops
				(best_length_ratio 0.4)
				(max_length 1)
				(best_width_ratio 0.9)
				(max_width 2)
				(curved_edges yes)
				(filter_ratio 0.9)
				(enabled yes)
				(allow_two_segments yes)
				(prefer_zone_connections yes)
			)
		)
		(pad "L11" thru_hole circle
			(at -3.4 2.29 270)
			(size 0.86 0.86)
			(drill 0.46)
			(layers "*.Cu" "*.Mask")
			(remove_unused_layers no)
			(net 1 "GND")
			(pinfunction "V_{EE}(R)")
			(pintype "passive")
			(teardrops
				(best_length_ratio 0.4)
				(max_length 1)
				(best_width_ratio 0.9)
				(max_width 2)
				(curved_edges yes)
				(filter_ratio 0.9)
				(enabled yes)
				(allow_two_segments yes)
				(prefer_zone_connections yes)
			)
		)
		(pad "L12" thru_hole circle
			(at -2.6 3.67 270)
			(size 0.86 0.86)
			(drill 0.46)
			(layers "*.Cu" "*.Mask")
			(remove_unused_layers no)
			(net 877 "/2xSFP+/SFI1.RX-")
			(pinfunction "RD-")
			(pintype "output")
			(teardrops
				(best_length_ratio 0.4)
				(max_length 1)
				(best_width_ratio 0.9)
				(max_width 2)
				(curved_edges yes)
				(filter_ratio 0.9)
				(enabled yes)
				(allow_two_segments yes)
				(prefer_zone_connections yes)
			)
		)
		(pad "L13" thru_hole circle
			(at -1.8 2.29 270)
			(size 0.86 0.86)
			(drill 0.46)
			(layers "*.Cu" "*.Mask")
			(remove_unused_layers no)
			(net 878 "/2xSFP+/SFI1.RX+")
			(pinfunction "RD+")
			(pintype "output")
			(teardrops
				(best_length_ratio 0.4)
				(max_length 1)
				(best_width_ratio 0.9)
				(max_width 2)
				(curved_edges yes)
				(filter_ratio 0.9)
				(enabled yes)
				(allow_two_segments yes)
				(prefer_zone_connections yes)
			)
		)
		(pad "L14" thru_hole circle
			(at -1 3.67 270)
			(size 0.86 0.86)
			(drill 0.46)
			(layers "*.Cu" "*.Mask")
			(remove_unused_layers no)
			(net 1 "GND")
			(pinfunction "V_{EE}(R)")
			(pintype "passive")
			(teardrops
				(best_length_ratio 0.4)
				(max_length 1)
				(best_width_ratio 0.9)
				(max_width 2)
				(curved_edges yes)
				(filter_ratio 0.9)
				(enabled yes)
				(allow_two_segments yes)
				(prefer_zone_connections yes)
			)
		)
		(pad "L15" thru_hole circle
			(at -0.2 2.29 270)
			(size 0.86 0.86)
			(drill 0.46)
			(layers "*.Cu" "*.Mask")
			(remove_unused_layers no)
			(net 2 "+3V3")
			(pinfunction "V_{CC}(R)")
			(pintype "power_in")
			(teardrops
				(best_length_ratio 0.4)
				(max_length 1)
				(best_width_ratio 0.9)
				(max_width 2)
				(curved_edges yes)
				(filter_ratio 0.9)
				(enabled yes)
				(allow_two_segments yes)
				(prefer_zone_connections yes)
			)
		)
		(pad "L16" thru_hole circle
			(at 0.6 3.67 270)
			(size 0.86 0.86)
			(drill 0.46)
			(layers "*.Cu" "*.Mask")
			(remove_unused_layers no)
			(net 2 "+3V3")
			(pinfunction "V_{CC}(T)")
			(pintype "power_in")
			(teardrops
				(best_length_ratio 0.4)
				(max_length 1)
				(best_width_ratio 0.9)
				(max_width 2)
				(curved_edges yes)
				(filter_ratio 0.9)
				(enabled yes)
				(allow_two_segments yes)
				(prefer_zone_connections yes)
			)
		)
		(pad "L17" thru_hole circle
			(at 1.4 2.29 270)
			(size 0.86 0.86)
			(drill 0.46)
			(layers "*.Cu" "*.Mask")
			(remove_unused_layers no)
			(net 1 "GND")
			(pinfunction "V_{EE}(T)")
			(pintype "passive")
			(teardrops
				(best_length_ratio 0.4)
				(max_length 1)
				(best_width_ratio 0.9)
				(max_width 2)
				(curved_edges yes)
				(filter_ratio 0.9)
				(enabled yes)
				(allow_two_segments yes)
				(prefer_zone_connections yes)
			)
		)
		(pad "L18" thru_hole circle
			(at 2.2 3.67 270)
			(size 0.86 0.86)
			(drill 0.46)
			(layers "*.Cu" "*.Mask")
			(remove_unused_layers no)
			(net 879 "/2xSFP+/SFI1.TX+")
			(pinfunction "TD+")
			(pintype "input")
			(teardrops
				(best_length_ratio 0.4)
				(max_length 1)
				(best_width_ratio 0.9)
				(max_width 2)
				(curved_edges yes)
				(filter_ratio 0.9)
				(enabled yes)
				(allow_two_segments yes)
				(prefer_zone_connections yes)
			)
		)
		(pad "L19" thru_hole circle
			(at 3 2.29 270)
			(size 0.86 0.86)
			(drill 0.46)
			(layers "*.Cu" "*.Mask")
			(remove_unused_layers no)
			(net 880 "/2xSFP+/SFI1.TX-")
			(pinfunction "TD-")
			(pintype "input")
			(teardrops
				(best_length_ratio 0.4)
				(max_length 1)
				(best_width_ratio 0.9)
				(max_width 2)
				(curved_edges yes)
				(filter_ratio 0.9)
				(enabled yes)
				(allow_two_segments yes)
				(prefer_zone_connections yes)
			)
		)
		(pad "L20" thru_hole circle
			(at 3.8 3.67 270)
			(size 0.86 0.86)
			(drill 0.46)
			(layers "*.Cu" "*.Mask")
			(remove_unused_layers no)
			(net 1 "GND")
			(pinfunction "V_{EE}(T)")
			(pintype "passive")
			(teardrops
				(best_length_ratio 0.4)
				(max_length 1)
				(best_width_ratio 0.9)
				(max_width 2)
				(curved_edges yes)
				(filter_ratio 0.9)
				(enabled yes)
				(allow_two_segments yes)
				(prefer_zone_connections yes)
			)
		)
		(pad "SH" thru_hole circle
			(at -7.125 10.1 270)
			(size 1.5 1.5)
			(drill 1.05)
			(layers "*.Cu" "*.Mask")
			(remove_unused_layers no)
			(net 53 "/2xSFP+/SH")
			(pinfunction "SH")
			(pintype "passive")
			(teardrops
				(best_length_ratio 0.4)
				(max_length 1)
				(best_width_ratio 0.9)
				(max_width 2)
				(curved_edges yes)
				(filter_ratio 0.9)
				(enabled yes)
				(allow_two_segments yes)
				(prefer_zone_connections yes)
			)
		)
		(pad "SH" thru_hole circle
			(at -7.125 18.1 270)
			(size 1.5 1.5)
			(drill 1.05)
			(layers "*.Cu" "*.Mask")
			(remove_unused_layers no)
			(net 53 "/2xSFP+/SH")
			(pinfunction "SH")
			(pintype "passive")
			(teardrops
				(best_length_ratio 0.4)
				(max_length 1)
				(best_width_ratio 0.9)
				(max_width 2)
				(curved_edges yes)
				(filter_ratio 0.9)
				(enabled yes)
				(allow_two_segments yes)
				(prefer_zone_connections yes)
			)
		)
		(pad "SH" thru_hole circle
			(at -7.125 26.1 270)
			(size 1.5 1.5)
			(drill 1.05)
			(layers "*.Cu" "*.Mask")
			(remove_unused_layers no)
			(net 53 "/2xSFP+/SH")
			(pinfunction "SH")
			(pintype "passive")
			(teardrops
				(best_length_ratio 0.4)
				(max_length 1)
				(best_width_ratio 0.9)
				(max_width 2)
				(curved_edges yes)
				(filter_ratio 0.9)
				(enabled yes)
				(allow_two_segments yes)
				(prefer_zone_connections yes)
			)
		)
		(pad "SH" thru_hole circle
			(at -7.125 34.1 270)
			(size 1.5 1.5)
			(drill 1.05)
			(layers "*.Cu" "*.Mask")
			(remove_unused_layers no)
			(net 53 "/2xSFP+/SH")
			(pinfunction "SH")
			(pintype "passive")
			(teardrops
				(best_length_ratio 0.4)
				(max_length 1)
				(best_width_ratio 0.9)
				(max_width 2)
				(curved_edges yes)
				(filter_ratio 0.9)
				(enabled yes)
				(allow_two_segments yes)
				(prefer_zone_connections yes)
			)
		)
		(pad "SH" thru_hole circle
			(at -7.125 42.1 270)
			(size 1.5 1.5)
			(drill 1.05)
			(layers "*.Cu" "*.Mask")
			(remove_unused_layers no)
			(net 53 "/2xSFP+/SH")
			(pinfunction "SH")
			(pintype "passive")
			(teardrops
				(best_length_ratio 0.4)
				(max_length 1)
				(best_width_ratio 0.9)
				(max_width 2)
				(curved_edges yes)
				(filter_ratio 0.9)
				(enabled yes)
				(allow_two_segments yes)
				(prefer_zone_connections yes)
			)
		)
		(pad "SH" thru_hole circle
			(at -4 -9.5 270)
			(size 1.5 1.5)
			(drill 1.05)
			(layers "*.Cu" "*.Mask")
			(remove_unused_layers no)
			(net 53 "/2xSFP+/SH")
			(pinfunction "SH")
			(pintype "passive")
			(teardrops
				(best_length_ratio 0.4)
				(max_length 1)
				(best_width_ratio 0.9)
				(max_width 2)
				(curved_edges yes)
				(filter_ratio 0.9)
				(enabled yes)
				(allow_two_segments yes)
				(prefer_zone_connections yes)
			)
		)
		(pad "SH" thru_hole circle
			(at 0 -9.525 270)
			(size 1.5 1.5)
			(drill 1.05)
			(layers "*.Cu" "*.Mask")
			(remove_unused_layers no)
			(net 53 "/2xSFP+/SH")
			(pinfunction "SH")
			(pintype "passive")
			(teardrops
				(best_length_ratio 0.4)
				(max_length 1)
				(best_width_ratio 0.9)
				(max_width 2)
				(curved_edges yes)
				(filter_ratio 0.9)
				(enabled yes)
				(allow_two_segments yes)
				(prefer_zone_connections yes)
			)
		)
		(pad "SH" thru_hole circle
			(at 4 -9.5 270)
			(size 1.5 1.5)
			(drill 1.05)
			(layers "*.Cu" "*.Mask")
			(remove_unused_layers no)
			(net 53 "/2xSFP+/SH")
			(pinfunction "SH")
			(pintype "passive")
			(teardrops
				(best_length_ratio 0.4)
				(max_length 1)
				(best_width_ratio 0.9)
				(max_width 2)
				(curved_edges yes)
				(filter_ratio 0.9)
				(enabled yes)
				(allow_two_segments yes)
				(prefer_zone_connections yes)
			)
		)
		(pad "SH" thru_hole circle
			(at 7.125 10.1 270)
			(size 1.5 1.5)
			(drill 1.05)
			(layers "*.Cu" "*.Mask")
			(remove_unused_layers no)
			(net 53 "/2xSFP+/SH")
			(pinfunction "SH")
			(pintype "passive")
			(teardrops
				(best_length_ratio 0.4)
				(max_length 1)
				(best_width_ratio 0.9)
				(max_width 2)
				(curved_edges yes)
				(filter_ratio 0.9)
				(enabled yes)
				(allow_two_segments yes)
				(prefer_zone_connections yes)
			)
		)
		(pad "SH" thru_hole circle
			(at 7.125 18.1 270)
			(size 1.5 1.5)
			(drill 1.05)
			(layers "*.Cu" "*.Mask")
			(remove_unused_layers no)
			(net 53 "/2xSFP+/SH")
			(pinfunction "SH")
			(pintype "passive")
			(teardrops
				(best_length_ratio 0.4)
				(max_length 1)
				(best_width_ratio 0.9)
				(max_width 2)
				(curved_edges yes)
				(filter_ratio 0.9)
				(enabled yes)
				(allow_two_segments yes)
				(prefer_zone_connections yes)
			)
		)
		(pad "SH" thru_hole circle
			(at 7.125 26.1 270)
			(size 1.5 1.5)
			(drill 1.05)
			(layers "*.Cu" "*.Mask")
			(remove_unused_layers no)
			(net 53 "/2xSFP+/SH")
			(pinfunction "SH")
			(pintype "passive")
			(teardrops
				(best_length_ratio 0.4)
				(max_length 1)
				(best_width_ratio 0.9)
				(max_width 2)
				(curved_edges yes)
				(filter_ratio 0.9)
				(enabled yes)
				(allow_two_segments yes)
				(prefer_zone_connections yes)
			)
		)
		(pad "SH" thru_hole circle
			(at 7.125 34.1 270)
			(size 1.5 1.5)
			(drill 1.05)
			(layers "*.Cu" "*.Mask")
			(remove_unused_layers no)
			(net 53 "/2xSFP+/SH")
			(pinfunction "SH")
			(pintype "passive")
			(teardrops
				(best_length_ratio 0.4)
				(max_length 1)
				(best_width_ratio 0.9)
				(max_width 2)
				(curved_edges yes)
				(filter_ratio 0.9)
				(enabled yes)
				(allow_two_segments yes)
				(prefer_zone_connections yes)
			)
		)
		(pad "SH" thru_hole circle
			(at 7.125 42.1 270)
			(size 1.5 1.5)
			(drill 1.05)
			(layers "*.Cu" "*.Mask")
			(remove_unused_layers no)
			(net 53 "/2xSFP+/SH")
			(pinfunction "SH")
			(pintype "passive")
			(teardrops
				(best_length_ratio 0.4)
				(max_length 1)
				(best_width_ratio 0.9)
				(max_width 2)
				(curved_edges yes)
				(filter_ratio 0.9)
				(enabled yes)
				(allow_two_segments yes)
				(prefer_zone_connections yes)
			)
		)
		(pad "T1" thru_hole circle
			(at -3.4 -3.58 270)
			(size 0.86 0.86)
			(drill 0.46)
			(layers "*.Cu" "*.Mask")
			(remove_unused_layers no)
			(net 1 "GND")
			(pinfunction "V_{EE}(T)")
			(pintype "passive")
			(teardrops
				(best_length_ratio 0.4)
				(max_length 1)
				(best_width_ratio 0.9)
				(max_width 2)
				(curved_edges yes)
				(filter_ratio 0.9)
				(enabled yes)
				(allow_two_segments yes)
				(prefer_zone_connections yes)
			)
		)
		(pad "T2" thru_hole circle
			(at -2.6 -2.2 270)
			(size 0.86 0.86)
			(drill 0.46)
			(layers "*.Cu" "*.Mask")
			(remove_unused_layers no)
			(net 162 "Net-(J2A-TX_{FAULT})")
			(pinfunction "TX_{FAULT}")
			(pintype "open_collector")
			(teardrops
				(best_length_ratio 0.4)
				(max_length 1)
				(best_width_ratio 0.9)
				(max_width 2)
				(curved_edges yes)
				(filter_ratio 0.9)
				(enabled yes)
				(allow_two_segments yes)
				(prefer_zone_connections yes)
			)
		)
		(pad "T3" thru_hole circle
			(at -1.8 -3.58 270)
			(size 0.86 0.86)
			(drill 0.46)
			(layers "*.Cu" "*.Mask")
			(remove_unused_layers no)
			(net 163 "Net-(J2A-TX_{DISABLE})")
			(pinfunction "TX_{DISABLE}")
			(pintype "input")
			(teardrops
				(best_length_ratio 0.4)
				(max_length 1)
				(best_width_ratio 0.9)
				(max_width 2)
				(curved_edges yes)
				(filter_ratio 0.9)
				(enabled yes)
				(allow_two_segments yes)
				(prefer_zone_connections yes)
			)
		)
		(pad "T4" thru_hole circle
			(at -1 -2.2 270)
			(size 0.86 0.86)
			(drill 0.46)
			(layers "*.Cu" "*.Mask")
			(remove_unused_layers no)
			(net 164 "/2xSFP+/SDA0")
			(pinfunction "SDA")
			(pintype "bidirectional")
			(teardrops
				(best_length_ratio 0.4)
				(max_length 1)
				(best_width_ratio 0.9)
				(max_width 2)
				(curved_edges yes)
				(filter_ratio 0.9)
				(enabled yes)
				(allow_two_segments yes)
				(prefer_zone_connections yes)
			)
		)
		(pad "T5" thru_hole circle
			(at -0.2 -3.58 270)
			(size 0.86 0.86)
			(drill 0.46)
			(layers "*.Cu" "*.Mask")
			(remove_unused_layers no)
			(net 165 "/2xSFP+/SCL0")
			(pinfunction "SCL")
			(pintype "bidirectional")
			(teardrops
				(best_length_ratio 0.4)
				(max_length 1)
				(best_width_ratio 0.9)
				(max_width 2)
				(curved_edges yes)
				(filter_ratio 0.9)
				(enabled yes)
				(allow_two_segments yes)
				(prefer_zone_connections yes)
			)
		)
	)
)
